(kicad_pcb
	(version 20260206)
	(generator "pcbnew")
	(generator_version "10.0")
	(general
		(thickness 1.6)
		(legacy_teardrops no)
	)
	(paper "A4")
	(title_block
		(title "Bryce Canyon_SCC_16316-1_OCP.brd")
		(comment 1 "Bryce Canyon / footprints 533-540 of 1561")
	)
	(layers
		(0 "F.Cu" signal "TOP")
		(4 "In1.Cu" signal "L2GND")
		(6 "In2.Cu" signal "L3")
		(8 "In3.Cu" signal "L4VCC")
		(10 "In4.Cu" signal "L5VCC")
		(12 "In5.Cu" signal "L6")
		(14 "In6.Cu" signal "L7GND")
		(2 "B.Cu" signal "BOTTOM")
		(9 "F.Adhes" user "F.Adhesive")
		(11 "B.Adhes" user "B.Adhesive")
		(13 "F.Paste" user "Package Geometry/Pastemask Top")
		(15 "B.Paste" user "Package Geometry/Pastemask Bottom")
		(5 "F.SilkS" user "Ref Des/Silkscreen Top")
		(7 "B.SilkS" user "Ref Des/Silkscreen Bottom")
		(1 "F.Mask" user "Board Geometry/Soldermask Top")
		(3 "B.Mask" user "Board Geometry/Soldermask Bottom")
		(17 "Dwgs.User" user "User.Drawings")
		(19 "Cmts.User" user "User.Comments")
		(21 "Eco1.User" user "User.Eco1")
		(23 "Eco2.User" user "User.Eco2")
		(25 "Edge.Cuts" user "Board Geometry/Outline")
		(27 "Margin" user)
		(31 "F.CrtYd" user "Package Geometry/Place Bound Top")
		(29 "B.CrtYd" user "Package Geometry/Place Bound Bottom")
		(35 "F.Fab" user "Ref Des/Assembly Top")
		(33 "B.Fab" user "Ref Des/Assembly Bottom")
	)
	(footprint ""
		(layer "F.Cu")
		(at 23.1902 -57.2516)
		(property "Reference" "R19"
			(at 0 0 0)
			(layer "F.SilkS")
			(hide yes)
			(effects
				(font
					(size 1.27 1.27)
				)
			)
		)
		(property "Value" "100KR2J-4-GP"
			(at 0.064008 -3.993896 0)
			(unlocked yes)
			(layer "F.Fab")
			(hide yes)
			(effects
				(font
					(size 1.016 1.016)
					(thickness 0.1524)
				)
			)
		)
		(property "Device Type" "R402H15"
			(at 0.064008 -5.517896 0)
			(unlocked yes)
			(layer "F.Fab")
			(hide yes)
			(effects
				(font
					(size 1.016 1.016)
					(thickness 0.1524)
				)
			)
		)
		(duplicate_pad_numbers_are_jumpers no)
		(fp_line
			(start -0.508 -0.9398)
			(end -0.508 0.9398)
			(stroke
				(width 0.1524)
				(type default)
			)
			(layer "F.SilkS")
		)
		(fp_line
			(start 0.508 -0.9398)
			(end -0.508 -0.9398)
			(stroke
				(width 0.1524)
				(type default)
			)
			(layer "F.SilkS")
		)
		(fp_rect
			(start -0.508 0.9398)
			(end 0.508 -0.9398)
			(stroke
				(width 0)
				(type default)
			)
			(fill no)
			(layer "F.CrtYd")
		)
		(fp_rect
			(start -0.508 0.9398)
			(end 0.508 -0.9398)
			(stroke
				(width 0)
				(type default)
			)
			(fill no)
			(layer "F.Fab")
		)
		(pad "1" smd custom
			(at 0 -0.4445)
			(size 0.1397 0.1397)
			(layers "F.Cu" "F.Mask" "F.Paste")
			(net "MB0_VCAP_R")
			(options
				(clearance outline)
				(anchor circle)
			)
			(primitives
				(gr_poly
					(pts
						(arc
							(start -0.1778 -0.2794)
							(mid -0.249642 -0.249642)
							(end -0.2794 -0.1778)
						)
						(arc
							(start -0.2794 0.1778)
							(mid -0.249642 0.249642)
							(end -0.1778 0.2794)
						)
						(arc
							(start 0.1778 0.2794)
							(mid 0.249642 0.249642)
							(end 0.2794 0.1778)
						)
						(arc
							(start 0.2794 -0.1778)
							(mid 0.249642 -0.249642)
							(end 0.1778 -0.2794)
						)
					)
					(width 0)
					(fill yes)
				)
			)
		)
		(pad "2" smd custom
			(at 0 0.4445)
			(size 0.1397 0.1397)
			(layers "F.Cu" "F.Mask" "F.Paste")
			(net "MB0_ISTART_R")
			(options
				(clearance outline)
				(anchor circle)
			)
			(primitives
				(gr_poly
					(pts
						(arc
							(start -0.1778 -0.2794)
							(mid -0.249642 -0.249642)
							(end -0.2794 -0.1778)
						)
						(arc
							(start -0.2794 0.1778)
							(mid -0.249642 0.249642)
							(end -0.1778 0.2794)
						)
						(arc
							(start 0.1778 0.2794)
							(mid 0.249642 0.249642)
							(end 0.2794 0.1778)
						)
						(arc
							(start 0.2794 -0.1778)
							(mid 0.249642 -0.249642)
							(end 0.1778 -0.2794)
						)
					)
					(width 0)
					(fill yes)
				)
			)
		)
	)
	(footprint ""
		(layer "F.Cu")
		(at 94.518226 -65.93332)
		(property "Reference" "R556"
			(at 0 0 0)
			(layer "F.SilkS")
			(hide yes)
			(effects
				(font
					(size 1.27 1.27)
				)
			)
		)
		(property "Value" "0R2J-2-GP"
			(at 0.064008 -3.993896 0)
			(unlocked yes)
			(layer "F.Fab")
			(hide yes)
			(effects
				(font
					(size 1.016 1.016)
					(thickness 0.1524)
				)
			)
		)
		(property "Device Type" "R402H16"
			(at 0.064008 -5.517896 0)
			(unlocked yes)
			(layer "F.Fab")
			(hide yes)
			(effects
				(font
					(size 1.016 1.016)
					(thickness 0.1524)
				)
			)
		)
		(duplicate_pad_numbers_are_jumpers no)
		(fp_line
			(start -0.508 -0.9398)
			(end -0.508 0.9398)
			(stroke
				(width 0.1524)
				(type default)
			)
			(layer "F.SilkS")
		)
		(fp_line
			(start 0.508 -0.9398)
			(end -0.508 -0.9398)
			(stroke
				(width 0.1524)
				(type default)
			)
			(layer "F.SilkS")
		)
		(fp_rect
			(start -0.508 0.9398)
			(end 0.508 -0.9398)
			(stroke
				(width 0)
				(type default)
			)
			(fill no)
			(layer "F.CrtYd")
		)
		(fp_rect
			(start -0.508 0.9398)
			(end 0.508 -0.9398)
			(stroke
				(width 0)
				(type default)
			)
			(fill no)
			(layer "F.Fab")
		)
		(pad "1" smd custom
			(at 0 -0.4445)
			(size 0.1397 0.1397)
			(layers "F.Cu" "F.Mask" "F.Paste")
			(net "GND")
			(options
				(clearance outline)
				(anchor circle)
			)
			(primitives
				(gr_poly
					(pts
						(arc
							(start -0.1778 -0.2794)
							(mid -0.249642 -0.249642)
							(end -0.2794 -0.1778)
						)
						(arc
							(start -0.2794 0.1778)
							(mid -0.249642 0.249642)
							(end -0.1778 0.2794)
						)
						(arc
							(start 0.1778 0.2794)
							(mid 0.249642 0.249642)
							(end 0.2794 0.1778)
						)
						(arc
							(start 0.2794 -0.1778)
							(mid 0.249642 -0.249642)
							(end 0.1778 -0.2794)
						)
					)
					(width 0)
					(fill yes)
				)
			)
		)
		(pad "2" smd custom
			(at 0 0.4445)
			(size 0.1397 0.1397)
			(layers "F.Cu" "F.Mask" "F.Paste")
			(net "LED47")
			(options
				(clearance outline)
				(anchor circle)
			)
			(primitives
				(gr_poly
					(pts
						(arc
							(start -0.1778 -0.2794)
							(mid -0.249642 -0.249642)
							(end -0.2794 -0.1778)
						)
						(arc
							(start -0.2794 0.1778)
							(mid -0.249642 0.249642)
							(end -0.1778 0.2794)
						)
						(arc
							(start 0.1778 0.2794)
							(mid 0.249642 0.249642)
							(end 0.2794 0.1778)
						)
						(arc
							(start 0.2794 -0.1778)
							(mid 0.249642 -0.249642)
							(end 0.1778 -0.2794)
						)
					)
					(width 0)
					(fill yes)
				)
			)
		)
	)
	(footprint ""
		(layer "F.Cu")
		(at 94.234 -69.977 -90)
		(property "Reference" "R108"
			(at 0 0 270)
			(layer "F.SilkS")
			(hide yes)
			(effects
				(font
					(size 1.27 1.27)
				)
			)
		)
		(property "Value" "4K75R2F-1-GP"
			(at 0.064008 -3.993896 270)
			(unlocked yes)
			(layer "F.Fab")
			(hide yes)
			(effects
				(font
					(size 1.016 1.016)
					(thickness 0.1524)
				)
			)
		)
		(property "Device Type" "R402H16"
			(at 0.064008 -5.517896 270)
			(unlocked yes)
			(layer "F.Fab")
			(hide yes)
			(effects
				(font
					(size 1.016 1.016)
					(thickness 0.1524)
				)
			)
		)
		(duplicate_pad_numbers_are_jumpers no)
		(fp_line
			(start -0.508 -0.9398)
			(end -0.508 0.9398)
			(stroke
				(width 0.1524)
				(type default)
			)
			(layer "F.SilkS")
		)
		(fp_line
			(start 0.508 -0.9398)
			(end -0.508 -0.9398)
			(stroke
				(width 0.1524)
				(type default)
			)
			(layer "F.SilkS")
		)
		(fp_rect
			(start -0.508 0.9398)
			(end 0.508 -0.9398)
			(stroke
				(width 0)
				(type default)
			)
			(fill no)
			(layer "F.CrtYd")
		)
		(fp_rect
			(start -0.508 0.9398)
			(end 0.508 -0.9398)
			(stroke
				(width 0)
				(type default)
			)
			(fill no)
			(layer "F.Fab")
		)
		(pad "1" smd custom
			(at 0 -0.4445 270)
			(size 0.1397 0.1397)
			(layers "F.Cu" "F.Mask" "F.Paste")
			(net "LSI_SCAN_ENABLE")
			(options
				(clearance outline)
				(anchor circle)
			)
			(primitives
				(gr_poly
					(pts
						(arc
							(start -0.1778 -0.2794)
							(mid -0.249642 -0.249642)
							(end -0.2794 -0.1778)
						)
						(arc
							(start -0.2794 0.1778)
							(mid -0.249642 0.249642)
							(end -0.1778 0.2794)
						)
						(arc
							(start 0.1778 0.2794)
							(mid 0.249642 0.249642)
							(end 0.2794 0.1778)
						)
						(arc
							(start 0.2794 -0.1778)
							(mid 0.249642 -0.249642)
							(end 0.1778 -0.2794)
						)
					)
					(width 0)
					(fill yes)
				)
			)
		)
		(pad "2" smd custom
			(at 0 0.4445 270)
			(size 0.1397 0.1397)
			(layers "F.Cu" "F.Mask" "F.Paste")
			(net "GND")
			(options
				(clearance outline)
				(anchor circle)
			)
			(primitives
				(gr_poly
					(pts
						(arc
							(start -0.1778 -0.2794)
							(mid -0.249642 -0.249642)
							(end -0.2794 -0.1778)
						)
						(arc
							(start -0.2794 0.1778)
							(mid -0.249642 0.249642)
							(end -0.1778 0.2794)
						)
						(arc
							(start 0.1778 0.2794)
							(mid 0.249642 0.249642)
							(end 0.2794 0.1778)
						)
						(arc
							(start 0.2794 -0.1778)
							(mid 0.249642 -0.249642)
							(end 0.1778 -0.2794)
						)
					)
					(width 0)
					(fill yes)
				)
			)
		)
	)
	(footprint ""
		(layer "F.Cu")
		(at 191.846708 -44.12361 -90)
		(property "Reference" "R237"
			(at 0 0 270)
			(layer "F.SilkS")
			(hide yes)
			(effects
				(font
					(size 1.27 1.27)
				)
			)
		)
		(property "Value" "10KR2F-2-GP"
			(at 0.064008 -3.993896 270)
			(unlocked yes)
			(layer "F.Fab")
			(hide yes)
			(effects
				(font
					(size 1.016 1.016)
					(thickness 0.1524)
				)
			)
		)
		(property "Device Type" "R402H16"
			(at 0.064008 -5.517896 270)
			(unlocked yes)
			(layer "F.Fab")
			(hide yes)
			(effects
				(font
					(size 1.016 1.016)
					(thickness 0.1524)
				)
			)
		)
		(duplicate_pad_numbers_are_jumpers no)
		(fp_line
			(start -0.508 -0.9398)
			(end -0.508 0.9398)
			(stroke
				(width 0.1524)
				(type default)
			)
			(layer "F.SilkS")
		)
		(fp_line
			(start 0.508 -0.9398)
			(end -0.508 -0.9398)
			(stroke
				(width 0.1524)
				(type default)
			)
			(layer "F.SilkS")
		)
		(fp_rect
			(start -0.508 0.9398)
			(end 0.508 -0.9398)
			(stroke
				(width 0)
				(type default)
			)
			(fill no)
			(layer "F.CrtYd")
		)
		(fp_rect
			(start -0.508 0.9398)
			(end 0.508 -0.9398)
			(stroke
				(width 0)
				(type default)
			)
			(fill no)
			(layer "F.Fab")
		)
		(pad "1" smd custom
			(at 0 -0.4445 270)
			(size 0.1397 0.1397)
			(layers "F.Cu" "F.Mask" "F.Paste")
			(net "GND")
			(options
				(clearance outline)
				(anchor circle)
			)
			(primitives
				(gr_poly
					(pts
						(arc
							(start -0.1778 -0.2794)
							(mid -0.249642 -0.249642)
							(end -0.2794 -0.1778)
						)
						(arc
							(start -0.2794 0.1778)
							(mid -0.249642 0.249642)
							(end -0.1778 0.2794)
						)
						(arc
							(start 0.1778 0.2794)
							(mid 0.249642 0.249642)
							(end 0.2794 0.1778)
						)
						(arc
							(start 0.2794 -0.1778)
							(mid 0.249642 -0.249642)
							(end 0.1778 -0.2794)
						)
					)
					(width 0)
					(fill yes)
				)
			)
		)
		(pad "2" smd custom
			(at 0 0.4445 270)
			(size 0.1397 0.1397)
			(layers "F.Cu" "F.Mask" "F.Paste")
			(net "MEM_CLK_SEL")
			(options
				(clearance outline)
				(anchor circle)
			)
			(primitives
				(gr_poly
					(pts
						(arc
							(start -0.1778 -0.2794)
							(mid -0.249642 -0.249642)
							(end -0.2794 -0.1778)
						)
						(arc
							(start -0.2794 0.1778)
							(mid -0.249642 0.249642)
							(end -0.1778 0.2794)
						)
						(arc
							(start 0.1778 0.2794)
							(mid 0.249642 0.249642)
							(end 0.2794 0.1778)
						)
						(arc
							(start 0.2794 -0.1778)
							(mid 0.249642 -0.249642)
							(end 0.1778 -0.2794)
						)
					)
					(width 0)
					(fill yes)
				)
			)
		)
	)
	(footprint ""
		(layer "F.Cu")
		(at 60.452 -45.847 90)
		(property "Reference" "L31"
			(at 0 0 90)
			(layer "F.SilkS")
			(hide yes)
			(effects
				(font
					(size 1.27 1.27)
				)
			)
		)
		(property "Value" "IND-180NH-8-GP"
			(at -5.273802 -3.640836 90)
			(unlocked yes)
			(layer "F.Fab")
			(hide yes)
			(effects
				(font
					(size 1.016 1.016)
					(thickness 0.1524)
				)
			)
		)
		(property "Device Type" "L105080-2221H276"
			(at -5.273802 -5.164836 90)
			(unlocked yes)
			(layer "F.Fab")
			(hide yes)
			(effects
				(font
					(size 1.016 1.016)
					(thickness 0.1524)
				)
			)
		)
		(duplicate_pad_numbers_are_jumpers no)
		(fp_line
			(start 4.2545 -5.8928)
			(end -4.2545 -5.8928)
			(stroke
				(width 0.1524)
				(type default)
			)
			(layer "F.SilkS")
		)
		(fp_line
			(start -4.2545 -5.8928)
			(end -4.2545 5.8928)
			(stroke
				(width 0.1524)
				(type default)
			)
			(layer "F.SilkS")
		)
		(fp_line
			(start 4.2545 5.8928)
			(end 4.2545 -5.8928)
			(stroke
				(width 0.1524)
				(type default)
			)
			(layer "F.SilkS")
		)
		(fp_line
			(start -4.2545 5.8928)
			(end 4.2545 5.8928)
			(stroke
				(width 0.1524)
				(type default)
			)
			(layer "F.SilkS")
		)
		(fp_rect
			(start -4.0005 5.2451)
			(end 4.0005 -5.2451)
			(stroke
				(width 0)
				(type default)
			)
			(fill no)
			(layer "F.CrtYd")
		)
		(fp_poly
			(pts
				(xy -4.5085 5.969) (xy -4.5085 -5.969) (xy 4.5085 -5.969) (xy 4.5085 -0.00254) (xy 4.0005 -0.00254)
				(xy 4.0005 -5.2451) (xy -4.0005 -5.2451) (xy -4.0005 5.2451) (xy 4.0005 5.2451) (xy 4.0005 0.00254)
				(xy 4.5085 0.00254) (xy 4.5085 5.969)
			)
			(stroke
				(width 0)
				(type default)
			)
			(fill no)
			(layer "F.CrtYd")
		)
		(fp_rect
			(start -4.5085 5.969)
			(end 4.5085 -5.969)
			(stroke
				(width 0)
				(type default)
			)
			(fill no)
			(layer "F.Fab")
		)
		(pad "1" smd rect
			(at 0 -4.095496 90)
			(size 2.3622 3.0988)
			(layers "F.Cu" "F.Mask" "F.Paste")
			(net "P0V9_VSW")
		)
		(pad "2" smd rect
			(at 0 4.095496 90)
			(size 2.3622 3.0988)
			(layers "F.Cu" "F.Mask" "F.Paste")
			(net "P0V9")
		)
	)
	(footprint ""
		(layer "F.Cu")
		(at 19.2278 -77.343 90)
		(property "Reference" "R351"
			(at 0 0 90)
			(layer "F.SilkS")
			(hide yes)
			(effects
				(font
					(size 1.27 1.27)
				)
			)
		)
		(property "Value" "0R2J-2-GP"
			(at 0.064008 -3.993896 90)
			(unlocked yes)
			(layer "F.Fab")
			(hide yes)
			(effects
				(font
					(size 1.016 1.016)
					(thickness 0.1524)
				)
			)
		)
		(property "Device Type" "R402H16"
			(at 0.064008 -5.517896 90)
			(unlocked yes)
			(layer "F.Fab")
			(hide yes)
			(effects
				(font
					(size 1.016 1.016)
					(thickness 0.1524)
				)
			)
		)
		(duplicate_pad_numbers_are_jumpers no)
		(fp_line
			(start 0.508 -0.9398)
			(end -0.508 -0.9398)
			(stroke
				(width 0.1524)
				(type default)
			)
			(layer "F.SilkS")
		)
		(fp_line
			(start -0.508 -0.9398)
			(end -0.508 0.9398)
			(stroke
				(width 0.1524)
				(type default)
			)
			(layer "F.SilkS")
		)
		(fp_rect
			(start -0.508 0.9398)
			(end 0.508 -0.9398)
			(stroke
				(width 0)
				(type default)
			)
			(fill no)
			(layer "F.CrtYd")
		)
		(fp_rect
			(start -0.508 0.9398)
			(end 0.508 -0.9398)
			(stroke
				(width 0)
				(type default)
			)
			(fill no)
			(layer "F.Fab")
		)
		(pad "1" smd custom
			(at 0 -0.4445 90)
			(size 0.1397 0.1397)
			(layers "F.Cu" "F.Mask" "F.Paste")
			(net "EXP_EEPROM_SDA")
			(options
				(clearance outline)
				(anchor circle)
			)
			(primitives
				(gr_poly
					(pts
						(arc
							(start -0.1778 -0.2794)
							(mid -0.249642 -0.249642)
							(end -0.2794 -0.1778)
						)
						(arc
							(start -0.2794 0.1778)
							(mid -0.249642 0.249642)
							(end -0.1778 0.2794)
						)
						(arc
							(start 0.1778 0.2794)
							(mid 0.249642 0.249642)
							(end 0.2794 0.1778)
						)
						(arc
							(start 0.2794 -0.1778)
							(mid 0.249642 -0.249642)
							(end 0.1778 -0.2794)
						)
					)
					(width 0)
					(fill yes)
				)
			)
		)
		(pad "2" smd custom
			(at 0 0.4445 90)
			(size 0.1397 0.1397)
			(layers "F.Cu" "F.Mask" "F.Paste")
			(net "I2C_SCC_SDA2")
			(options
				(clearance outline)
				(anchor circle)
			)
			(primitives
				(gr_poly
					(pts
						(arc
							(start -0.1778 -0.2794)
							(mid -0.249642 -0.249642)
							(end -0.2794 -0.1778)
						)
						(arc
							(start -0.2794 0.1778)
							(mid -0.249642 0.249642)
							(end -0.1778 0.2794)
						)
						(arc
							(start 0.1778 0.2794)
							(mid 0.249642 0.249642)
							(end 0.2794 0.1778)
						)
						(arc
							(start 0.2794 -0.1778)
							(mid 0.249642 -0.249642)
							(end 0.1778 -0.2794)
						)
					)
					(width 0)
					(fill yes)
				)
			)
		)
	)
	(footprint ""
		(layer "F.Cu")
		(at 175.5394 -59.817)
		(property "Reference" "R247"
			(at 0 0 0)
			(layer "F.SilkS")
			(hide yes)
			(effects
				(font
					(size 1.27 1.27)
				)
			)
		)
		(property "Value" "4K7R2F-GP"
			(at 0.064008 -3.993896 0)
			(unlocked yes)
			(layer "F.Fab")
			(hide yes)
			(effects
				(font
					(size 1.016 1.016)
					(thickness 0.1524)
				)
			)
		)
		(property "Device Type" "R402H16"
			(at 0.064008 -5.517896 0)
			(unlocked yes)
			(layer "F.Fab")
			(hide yes)
			(effects
				(font
					(size 1.016 1.016)
					(thickness 0.1524)
				)
			)
		)
		(duplicate_pad_numbers_are_jumpers no)
		(fp_line
			(start -0.508 -0.9398)
			(end -0.508 0.9398)
			(stroke
				(width 0.1524)
				(type default)
			)
			(layer "F.SilkS")
		)
		(fp_line
			(start 0.508 -0.9398)
			(end -0.508 -0.9398)
			(stroke
				(width 0.1524)
				(type default)
			)
			(layer "F.SilkS")
		)
		(fp_rect
			(start -0.508 0.9398)
			(end 0.508 -0.9398)
			(stroke
				(width 0)
				(type default)
			)
			(fill no)
			(layer "F.CrtYd")
		)
		(fp_rect
			(start -0.508 0.9398)
			(end 0.508 -0.9398)
			(stroke
				(width 0)
				(type default)
			)
			(fill no)
			(layer "F.Fab")
		)
		(pad "1" smd custom
			(at 0 -0.4445)
			(size 0.1397 0.1397)
			(layers "F.Cu" "F.Mask" "F.Paste")
			(net "P1V8_C")
			(options
				(clearance outline)
				(anchor circle)
			)
			(primitives
				(gr_poly
					(pts
						(arc
							(start -0.1778 -0.2794)
							(mid -0.249642 -0.249642)
							(end -0.2794 -0.1778)
						)
						(arc
							(start -0.2794 0.1778)
							(mid -0.249642 0.249642)
							(end -0.1778 0.2794)
						)
						(arc
							(start 0.1778 0.2794)
							(mid 0.249642 0.249642)
							(end 0.2794 0.1778)
						)
						(arc
							(start 0.2794 -0.1778)
							(mid 0.249642 -0.249642)
							(end 0.1778 -0.2794)
						)
					)
					(width 0)
					(fill yes)
				)
			)
		)
		(pad "2" smd custom
			(at 0 0.4445)
			(size 0.1397 0.1397)
			(layers "F.Cu" "F.Mask" "F.Paste")
			(net "LSI_SCAN_EN")
			(options
				(clearance outline)
				(anchor circle)
			)
			(primitives
				(gr_poly
					(pts
						(arc
							(start -0.1778 -0.2794)
							(mid -0.249642 -0.249642)
							(end -0.2794 -0.1778)
						)
						(arc
							(start -0.2794 0.1778)
							(mid -0.249642 0.249642)
							(end -0.1778 0.2794)
						)
						(arc
							(start 0.1778 0.2794)
							(mid 0.249642 0.249642)
							(end 0.2794 0.1778)
						)
						(arc
							(start 0.2794 -0.1778)
							(mid 0.249642 -0.249642)
							(end 0.1778 -0.2794)
						)
					)
					(width 0)
					(fill yes)
				)
			)
		)
	)
	(footprint ""
		(layer "F.Cu")
		(at 124.6632 -111.28248)
		(property "Reference" "TP24"
			(at 0 0 0)
			(layer "F.SilkS")
			(hide yes)
			(effects
				(font
					(size 1.27 1.27)
				)
			)
		)
		(property "Value" "TPAD28-2-GP"
			(at -0.0127 -1.6637 0)
			(unlocked yes)
			(layer "F.Fab")
			(hide yes)
			(effects
				(font
					(size 1.016 1.016)
					(thickness 0.1524)
				)
			)
		)
		(property "Device Type" "TPAD28"
			(at -0.0127 -3.1877 0)
			(unlocked yes)
			(layer "F.Fab")
			(hide yes)
			(effects
				(font
					(size 1.016 1.016)
					(thickness 0.1524)
				)
			)
		)
		(duplicate_pad_numbers_are_jumpers no)
		(fp_poly
			(pts
				(arc
					(start 0.3556 0)
					(mid -0.3556 0)
					(end 0.3556 0)
				)
			)
			(stroke
				(width 0)
				(type default)
			)
			(fill no)
			(layer "F.CrtYd")
		)
		(fp_poly
			(pts
				(arc
					(start 0.6096 0)
					(mid -0.6096 0)
					(end 0.6096 0)
				)
			)
			(stroke
				(width 0)
				(type default)
			)
			(fill no)
			(layer "F.Fab")
		)
		(pad "1" smd circle
			(at 0 0)
			(size 0.7112 0.7112)
			(layers "F.Cu" "F.Mask" "F.Paste")
			(net "INT_B2_CONN1")
		)
	)
)
